(kicad_pcb
	(version 20260206)
	(generator "pcbnew")
	(generator_version "10.0")
	(general
		(thickness 1.6)
		(legacy_teardrops no)
	)
	(paper "A4")
	(title_block
		(title "timecard-production-celestica-r4006 — R4006-B0001-02_R01.brd")
		(comment 1 "Time Appliance Project (Time Card) / footprints 548-551 of 1113")
	)
	(layers
		(0 "F.Cu" signal "TOP")
		(4 "In1.Cu" signal "L02_GND1")
		(6 "In2.Cu" signal "L03_SIG1")
		(8 "In3.Cu" signal "L04_GND2")
		(10 "In4.Cu" signal "L05_VCC1")
		(12 "In5.Cu" signal "L06_VCC2")
		(14 "In6.Cu" signal "L07_GND3")
		(16 "In7.Cu" signal "L08_SIG2")
		(18 "In8.Cu" signal "L09_GND4")
		(2 "B.Cu" signal "BOTTOM")
		(9 "F.Adhes" user "F.Adhesive")
		(11 "B.Adhes" user "B.Adhesive")
		(13 "F.Paste" user "Package Geometry/Pastemask Top")
		(15 "B.Paste" user "Package Geometry/Pastemask Bottom")
		(5 "F.SilkS" user "Ref Des/Silkscreen Top")
		(7 "B.SilkS" user "Ref Des/Silkscreen Bottom")
		(1 "F.Mask" user "Board Geometry/Soldermask Top")
		(3 "B.Mask" user "Board Geometry/Soldermask Bottom")
		(17 "Dwgs.User" user "User.Drawings")
		(19 "Cmts.User" user "User.Comments")
		(21 "Eco1.User" user "User.Eco1")
		(23 "Eco2.User" user "User.Eco2")
		(25 "Edge.Cuts" user "Board Geometry/Outline")
		(27 "Margin" user)
		(31 "F.CrtYd" user "Package Geometry/Place Bound Top")
		(29 "B.CrtYd" user "Package Geometry/Place Bound Bottom")
		(35 "F.Fab" user "Ref Des/Assembly Top")
		(33 "B.Fab" user "Ref Des/Assembly Bottom")
	)
	(footprint ""
		(layer "F.Cu")
		(at 85.1662 -101.9048 -90)
		(property "Reference" "U6"
			(at -0.3302 -2.88417 90)
			(unlocked yes)
			(layer "F.SilkS")
			(effects
				(font
					(size 0.7874 0.5842)
					(thickness 0.1524)
				)
			)
		)
		(property "Value" ""
			(at 0 0 270)
			(layer "F.Fab")
			(effects
				(font
					(size 1.27 1.27)
				)
			)
		)
		(property "Device Type" "TPS54824RNVR_VQFN18-G220-10657A"
			(at 0.33782 4.521454 270)
			(unlocked yes)
			(layer "F.Fab")
			(hide yes)
			(effects
				(font
					(size 0.7874 0.5842)
					(thickness 0.1524)
				)
			)
		)
		(property "User Part Number" "PARTNUM*"
			(at 0.33782 5.715254 270)
			(unlocked yes)
			(layer "Cmts.User")
			(hide yes)
			(effects
				(font
					(size 0.7874 0.5842)
					(thickness 0.1524)
				)
			)
		)
		(duplicate_pad_numbers_are_jumpers no)
		(fp_line
			(start -2.208784 2.200148)
			(end -2.208784 -2.208784)
			(stroke
				(width 0.1)
				(type default)
			)
			(layer "F.SilkS")
		)
		(fp_line
			(start 2.208784 2.200148)
			(end -2.208784 2.200148)
			(stroke
				(width 0.1)
				(type default)
			)
			(layer "F.SilkS")
		)
		(fp_line
			(start -2.208784 -2.208784)
			(end 2.208784 -2.208784)
			(stroke
				(width 0.1)
				(type default)
			)
			(layer "F.SilkS")
		)
		(fp_line
			(start 2.208784 -2.208784)
			(end 2.208784 2.200148)
			(stroke
				(width 0.1)
				(type default)
			)
			(layer "F.SilkS")
		)
		(fp_poly
			(pts
				(arc
					(start -3.084068 -1.50114)
					(mid -3.084068 -0.48514)
					(end -3.084068 -1.50114)
				)
			)
			(stroke
				(width 0)
				(type default)
			)
			(fill yes)
			(layer "F.SilkS")
		)
		(fp_rect
			(start 2.462784 2.454148)
			(end -2.462784 -2.462784)
			(stroke
				(width 0)
				(type default)
			)
			(fill no)
			(layer "F.CrtYd")
		)
		(fp_line
			(start -1.800098 1.800098)
			(end -1.800098 -1.800098)
			(stroke
				(width 0.1)
				(type default)
			)
			(layer "F.Fab")
		)
		(fp_line
			(start 1.800098 1.800098)
			(end -1.800098 1.800098)
			(stroke
				(width 0.1)
				(type default)
			)
			(layer "F.Fab")
		)
		(fp_line
			(start -1.800098 -1.800098)
			(end 1.800098 -1.800098)
			(stroke
				(width 0.1)
				(type default)
			)
			(layer "F.Fab")
		)
		(fp_line
			(start 1.800098 -1.800098)
			(end 1.800098 1.800098)
			(stroke
				(width 0.1)
				(type default)
			)
			(layer "F.Fab")
		)
		(fp_circle
			(center -2.468626 -1.148334)
			(end -2.468626 -1.656334)
			(stroke
				(width 0.1)
				(type default)
			)
			(fill no)
			(layer "F.Fab")
		)
		(fp_text user "8"
			(at 1.98755 2.9972 0)
			(unlocked yes)
			(layer "F.SilkS")
			(effects
				(font
					(size 0.635 0.4064)
					(thickness 0.1524)
				)
			)
		)
		(fp_text user "7"
			(at 0.71755 2.7432 0)
			(unlocked yes)
			(layer "F.SilkS")
			(effects
				(font
					(size 0.635 0.4064)
					(thickness 0.1524)
				)
			)
		)
		(fp_text user "5"
			(at -1.49225 2.6162 0)
			(unlocked yes)
			(layer "F.SilkS")
			(effects
				(font
					(size 0.635 0.4064)
					(thickness 0.1524)
				)
			)
		)
		(fp_text user "6"
			(at -0.34925 2.6162 0)
			(unlocked yes)
			(layer "F.SilkS")
			(effects
				(font
					(size 0.635 0.4064)
					(thickness 0.1524)
				)
			)
		)
		(fp_text user "12"
			(at 2.87655 -1.9558 0)
			(unlocked yes)
			(layer "F.SilkS")
			(effects
				(font
					(size 0.635 0.4064)
					(thickness 0.1524)
				)
			)
		)
		(fp_text user "18"
			(at -2.3622 -2.87655 90)
			(unlocked yes)
			(layer "F.SilkS")
			(effects
				(font
					(size 0.635 0.4064)
					(thickness 0.1524)
				)
			)
		)
		(fp_text user "13"
			(at 1.5748 -2.87655 90)
			(unlocked yes)
			(layer "F.SilkS")
			(effects
				(font
					(size 0.635 0.4064)
					(thickness 0.1524)
				)
			)
		)
		(fp_text user "6"
			(at -1.06553 2.3622 0)
			(unlocked yes)
			(layer "F.Fab")
			(effects
				(font
					(size 0.7874 0.5842)
					(thickness 0.1524)
				)
			)
		)
		(fp_text user "7"
			(at 1.09347 2.3622 0)
			(unlocked yes)
			(layer "F.Fab")
			(effects
				(font
					(size 0.7874 0.5842)
					(thickness 0.1524)
				)
			)
		)
		(fp_text user "5"
			(at -2.08153 2.1082 0)
			(unlocked yes)
			(layer "F.Fab")
			(effects
				(font
					(size 0.7874 0.5842)
					(thickness 0.1524)
				)
			)
		)
		(fp_text user "8"
			(at 2.36347 1.8542 0)
			(unlocked yes)
			(layer "F.Fab")
			(effects
				(font
					(size 0.7874 0.5842)
					(thickness 0.1524)
				)
			)
		)
		(fp_text user "12"
			(at 2.36347 -1.1938 0)
			(unlocked yes)
			(layer "F.Fab")
			(effects
				(font
					(size 0.7874 0.5842)
					(thickness 0.1524)
				)
			)
		)
		(fp_text user "18"
			(at -1.604264 -2.61747 0)
			(unlocked yes)
			(layer "F.Fab")
			(effects
				(font
					(size 0.7874 0.5842)
					(thickness 0.1524)
				)
			)
		)
		(fp_text user "13"
			(at 1.356868 -2.61747 0)
			(unlocked yes)
			(layer "F.Fab")
			(effects
				(font
					(size 0.7874 0.5842)
					(thickness 0.1524)
				)
			)
		)
		(pad "1" smd rect
			(at -1.649984 -0.94996 270)
			(size 0.6096 0.3048)
			(layers "F.Cu" "F.Mask" "F.Paste")
			(net "XP3R3V_BT")
		)
		(pad "2" smd rect
			(at -1.374902 -0.350012 270)
			(size 1.143 0.4064)
			(layers "F.Cu" "F.Mask" "F.Paste")
			(net "VIN_XP3R3")
		)
		(pad "3" smd rect
			(at -1.374902 0.299974 270)
			(size 1.143 0.3048)
			(layers "F.Cu" "F.Mask" "F.Paste")
			(net "SG")
		)
		(pad "4" smd rect
			(at -1.374902 0.849884 270)
			(size 1.143 0.3048)
			(layers "F.Cu" "F.Mask" "F.Paste")
			(net "SG")
		)
		(pad "5" smd rect
			(at -1.374902 1.400048 270)
			(size 1.143 0.3048)
			(layers "F.Cu" "F.Mask" "F.Paste")
			(net "SG")
		)
		(pad "6" smd rect
			(at -0.32512 0.599948 270)
			(size 0.2032 2.6924)
			(layers "F.Cu" "F.Mask" "F.Paste")
			(net "XP3R3V_SW")
		)
		(pad "7" smd rect
			(at 0.32512 0.599948 270)
			(size 0.2032 2.6924)
			(layers "F.Cu" "F.Mask" "F.Paste")
			(net "XP3R3V_SW")
		)
		(pad "8" smd rect
			(at 1.374902 1.400048 270)
			(size 1.143 0.3048)
			(layers "F.Cu" "F.Mask" "F.Paste")
			(net "SG")
		)
		(pad "9" smd rect
			(at 1.374902 0.849884 270)
			(size 1.143 0.3048)
			(layers "F.Cu" "F.Mask" "F.Paste")
			(net "SG")
		)
		(pad "10" smd rect
			(at 1.374902 0.299974 270)
			(size 1.143 0.3048)
			(layers "F.Cu" "F.Mask" "F.Paste")
			(net "SG")
		)
		(pad "11" smd rect
			(at 1.374902 -0.350012 270)
			(size 1.143 0.4064)
			(layers "F.Cu" "F.Mask" "F.Paste")
			(net "VIN_XP3R3")
		)
		(pad "12" smd rect
			(at 1.649984 -0.94996 270)
			(size 0.6096 0.3048)
			(layers "F.Cu" "F.Mask" "F.Paste")
			(net "XP3R3V_AGND")
		)
		(pad "13" smd rect
			(at 1.374902 -1.649984 270)
			(size 0.508 0.6096)
			(layers "F.Cu" "F.Mask" "F.Paste")
			(net "XP3R3V_RT")
		)
		(pad "14" smd rect
			(at 0.750062 -1.649984 270)
			(size 0.254 0.6096)
			(layers "F.Cu" "F.Mask" "F.Paste")
			(net "XP3R3V_FB_R_TO_AGND")
		)
		(pad "15" smd rect
			(at 0.249936 -1.649984 270)
			(size 0.254 0.6096)
			(layers "F.Cu" "F.Mask" "F.Paste")
			(net "XP3R3V_COMP")
		)
		(pad "16" smd rect
			(at -0.249936 -1.649984 270)
			(size 0.254 0.6096)
			(layers "F.Cu" "F.Mask" "F.Paste")
			(net "XP3R3V_SS")
		)
		(pad "17" smd rect
			(at -0.750062 -1.649984 270)
			(size 0.254 0.6096)
			(layers "F.Cu" "F.Mask" "F.Paste")
			(net "XP3R3V_EN")
		)
		(pad "18" smd rect
			(at -1.374902 -1.649984 270)
			(size 0.508 0.6096)
			(layers "F.Cu" "F.Mask" "F.Paste")
			(net "R_XP3R3V_PG")
		)
	)
	(footprint ""
		(layer "F.Cu")
		(at 105.8164 -70.9168 180)
		(property "Reference" "C237"
			(at -0.381 -3.59537 0)
			(unlocked yes)
			(layer "F.SilkS")
			(effects
				(font
					(size 0.7874 0.5842)
					(thickness 0.1524)
				)
			)
		)
		(property "Value" "VAL*"
			(at 0.0762 2.067306 180)
			(unlocked yes)
			(layer "F.Fab")
			(hide yes)
			(effects
				(font
					(size 0.7874 0.5842)
					(thickness 0.1524)
				)
			)
		)
		(property "Device Type" "CAPACITOR-G105-0B104-CK,0.1UF,A"
			(at 0.0508 1.127506 180)
			(unlocked yes)
			(layer "F.Fab")
			(hide yes)
			(effects
				(font
					(size 0.7874 0.5842)
					(thickness 0.1524)
				)
			)
		)
		(property "User Part Number" "PARTNUM*"
			(at 0.1016 4.023106 180)
			(unlocked yes)
			(layer "Cmts.User")
			(hide yes)
			(effects
				(font
					(size 0.7874 0.5842)
					(thickness 0.1524)
				)
			)
		)
		(property "Tolerance" "TOL*"
			(at 0.0762 3.032506 180)
			(unlocked yes)
			(layer "Cmts.User")
			(hide yes)
			(effects
				(font
					(size 0.7874 0.5842)
					(thickness 0.1524)
				)
			)
		)
		(duplicate_pad_numbers_are_jumpers no)
		(fp_line
			(start 1.143 0.5588)
			(end 1.143 -0.5588)
			(stroke
				(width 0.1)
				(type default)
			)
			(layer "F.SilkS")
		)
		(fp_line
			(start 1.143 -0.5588)
			(end -1.143 -0.5588)
			(stroke
				(width 0.1)
				(type default)
			)
			(layer "F.SilkS")
		)
		(fp_line
			(start -1.143 0.5588)
			(end 1.143 0.5588)
			(stroke
				(width 0.1)
				(type default)
			)
			(layer "F.SilkS")
		)
		(fp_line
			(start -1.143 -0.5588)
			(end -1.143 0.5588)
			(stroke
				(width 0.1)
				(type default)
			)
			(layer "F.SilkS")
		)
		(fp_rect
			(start -1.143 0.5588)
			(end 1.143 -0.5588)
			(stroke
				(width 0)
				(type default)
			)
			(fill no)
			(layer "F.CrtYd")
		)
		(fp_line
			(start 0.508 0.3048)
			(end 0.508 -0.3048)
			(stroke
				(width 0.1)
				(type default)
			)
			(layer "F.Fab")
		)
		(fp_line
			(start 0.508 -0.3048)
			(end -0.508 -0.3048)
			(stroke
				(width 0.1)
				(type default)
			)
			(layer "F.Fab")
		)
		(fp_line
			(start -0.508 0.3048)
			(end 0.508 0.3048)
			(stroke
				(width 0.1)
				(type default)
			)
			(layer "F.Fab")
		)
		(fp_line
			(start -0.508 -0.3048)
			(end -0.508 0.3048)
			(stroke
				(width 0.1)
				(type default)
			)
			(layer "F.Fab")
		)
		(pad "1" smd rect
			(at -0.5334 0 180)
			(size 0.7112 0.6096)
			(layers "F.Cu" "F.Mask" "F.Paste")
			(net "XP3R3V_FPGA")
		)
		(pad "2" smd rect
			(at 0.5334 0 180)
			(size 0.7112 0.6096)
			(layers "F.Cu" "F.Mask" "F.Paste")
			(net "SG")
		)
		(zone
			(layer "F.Cu")
			(hatch none 0.5)
			(connect_pads
				(clearance 0)
			)
			(min_thickness 0.25)
			(keepout
				(tracks allowed)
				(vias not_allowed)
				(pads allowed)
				(copperpour not_allowed)
				(footprints allowed)
			)
			(placement
				(enabled no)
				(sheetname "")
			)
			(fill
				(thermal_gap 0.5)
				(thermal_bridge_width 0.5)
				(island_removal_mode 0)
			)
			(polygon
				(pts
					(xy 105.8926 -71.2216) (xy 105.7402 -71.2216) (xy 105.7402 -70.612) (xy 105.8926 -70.612)
				)
			)
		)
	)
	(footprint ""
		(layer "F.Cu")
		(at 94.107 -61.087 -90)
		(property "Reference" "C250"
			(at 2.794 0.08763 90)
			(unlocked yes)
			(layer "F.SilkS")
			(effects
				(font
					(size 0.7874 0.5842)
					(thickness 0.1524)
				)
			)
		)
		(property "Value" "VAL*"
			(at 0.0762 2.067306 270)
			(unlocked yes)
			(layer "F.Fab")
			(hide yes)
			(effects
				(font
					(size 0.7874 0.5842)
					(thickness 0.1524)
				)
			)
		)
		(property "Tolerance" "TOL*"
			(at 0.0762 3.032506 270)
			(unlocked yes)
			(layer "Cmts.User")
			(hide yes)
			(effects
				(font
					(size 0.7874 0.5842)
					(thickness 0.1524)
				)
			)
		)
		(property "User Part Number" "PARTNUM*"
			(at 0.1016 4.023106 270)
			(unlocked yes)
			(layer "Cmts.User")
			(hide yes)
			(effects
				(font
					(size 0.7874 0.5842)
					(thickness 0.1524)
				)
			)
		)
		(property "Device Type" "CAPACITOR-G105-0B104-EK,0.1UF,A"
			(at 0.0508 1.127506 270)
			(unlocked yes)
			(layer "F.Fab")
			(hide yes)
			(effects
				(font
					(size 0.7874 0.5842)
					(thickness 0.1524)
				)
			)
		)
		(duplicate_pad_numbers_are_jumpers no)
		(fp_line
			(start -1.143 0.5588)
			(end 1.143 0.5588)
			(stroke
				(width 0.1)
				(type default)
			)
			(layer "F.SilkS")
		)
		(fp_line
			(start 1.143 0.5588)
			(end 1.143 -0.5588)
			(stroke
				(width 0.1)
				(type default)
			)
			(layer "F.SilkS")
		)
		(fp_line
			(start -1.143 -0.5588)
			(end -1.143 0.5588)
			(stroke
				(width 0.1)
				(type default)
			)
			(layer "F.SilkS")
		)
		(fp_line
			(start 1.143 -0.5588)
			(end -1.143 -0.5588)
			(stroke
				(width 0.1)
				(type default)
			)
			(layer "F.SilkS")
		)
		(fp_poly
			(pts
				(xy -1.143 0.5588) (xy 1.143 0.5588) (xy 1.143 -0.5588) (xy -1.143 -0.5588)
			)
			(stroke
				(width 0)
				(type default)
			)
			(fill no)
			(layer "F.CrtYd")
		)
		(fp_line
			(start -0.508 0.3048)
			(end 0.508 0.3048)
			(stroke
				(width 0.1)
				(type default)
			)
			(layer "F.Fab")
		)
		(fp_line
			(start 0.508 0.3048)
			(end 0.508 -0.3048)
			(stroke
				(width 0.1)
				(type default)
			)
			(layer "F.Fab")
		)
		(fp_line
			(start -0.508 -0.3048)
			(end -0.508 0.3048)
			(stroke
				(width 0.1)
				(type default)
			)
			(layer "F.Fab")
		)
		(fp_line
			(start 0.508 -0.3048)
			(end -0.508 -0.3048)
			(stroke
				(width 0.1)
				(type default)
			)
			(layer "F.Fab")
		)
		(pad "1" smd rect
			(at -0.5334 0 270)
			(size 0.7112 0.6096)
			(layers "F.Cu" "F.Mask" "F.Paste")
			(net "UNNAMED_3_RESISTOR_I151_2")
		)
		(pad "2" smd rect
			(at 0.5334 0 270)
			(size 0.7112 0.6096)
			(layers "F.Cu" "F.Mask" "F.Paste")
			(net "SG")
		)
		(zone
			(layer "F.Cu")
			(hatch none 0.5)
			(connect_pads
				(clearance 0)
			)
			(min_thickness 0.25)
			(keepout
				(tracks not_allowed)
				(vias allowed)
				(pads allowed)
				(copperpour not_allowed)
				(footprints allowed)
			)
			(placement
				(enabled no)
				(sheetname "")
			)
			(fill
				(thermal_gap 0.5)
				(thermal_bridge_width 0.5)
				(island_removal_mode 0)
			)
			(polygon
				(pts
					(xy 93.8022 -61.1632) (xy 93.8022 -61.0108) (xy 94.4118 -61.0108) (xy 94.4118 -61.1632)
				)
			)
		)
		(zone
			(layer "F.Cu")
			(hatch none 0.5)
			(connect_pads
				(clearance 0)
			)
			(min_thickness 0.25)
			(keepout
				(tracks allowed)
				(vias not_allowed)
				(pads allowed)
				(copperpour not_allowed)
				(footprints allowed)
			)
			(placement
				(enabled no)
				(sheetname "")
			)
			(fill
				(thermal_gap 0.5)
				(thermal_bridge_width 0.5)
				(island_removal_mode 0)
			)
			(polygon
				(pts
					(xy 93.8022 -61.1632) (xy 93.8022 -61.0108) (xy 94.4118 -61.0108) (xy 94.4118 -61.1632)
				)
			)
		)
	)
	(footprint ""
		(layer "F.Cu")
		(at 57.4294 -103.4034 90)
		(property "Reference" "C15"
			(at -0.0254 3.18897 90)
			(unlocked yes)
			(layer "F.SilkS")
			(effects
				(font
					(size 0.7874 0.5842)
					(thickness 0.1524)
				)
			)
		)
		(property "Value" "VAL*"
			(at 0.0762 3.134106 90)
			(unlocked yes)
			(layer "F.Fab")
			(hide yes)
			(effects
				(font
					(size 0.7874 0.5842)
					(thickness 0.1524)
				)
			)
		)
		(property "Device Type" "CAPACITOR-G107-0F226-CM,22UF,2A"
			(at 0.0508 2.194306 90)
			(unlocked yes)
			(layer "F.Fab")
			(hide yes)
			(effects
				(font
					(size 0.7874 0.5842)
					(thickness 0.1524)
				)
			)
		)
		(property "User Part Number" "PARTNUM*"
			(at 0.1016 5.013706 90)
			(unlocked yes)
			(layer "Cmts.User")
			(hide yes)
			(effects
				(font
					(size 0.7874 0.5842)
					(thickness 0.1524)
				)
			)
		)
		(property "Tolerance" "TOL*"
			(at 0.0762 4.048506 90)
			(unlocked yes)
			(layer "Cmts.User")
			(hide yes)
			(effects
				(font
					(size 0.7874 0.5842)
					(thickness 0.1524)
				)
			)
		)
		(duplicate_pad_numbers_are_jumpers no)
		(fp_line
			(start 1.5748 -0.9398)
			(end -1.5748 -0.9398)
			(stroke
				(width 0.1)
				(type default)
			)
			(layer "F.SilkS")
		)
		(fp_line
			(start -1.5748 -0.9398)
			(end -1.5748 0.9398)
			(stroke
				(width 0.1)
				(type default)
			)
			(layer "F.SilkS")
		)
		(fp_line
			(start 1.5748 0.9398)
			(end 1.5748 -0.9398)
			(stroke
				(width 0.1)
				(type default)
			)
			(layer "F.SilkS")
		)
		(fp_line
			(start -1.5748 0.9398)
			(end 1.5748 0.9398)
			(stroke
				(width 0.1)
				(type default)
			)
			(layer "F.SilkS")
		)
		(fp_rect
			(start 1.5748 0.9398)
			(end -1.5748 -0.9398)
			(stroke
				(width 0)
				(type default)
			)
			(fill no)
			(layer "F.CrtYd")
		)
		(fp_line
			(start 1.016 -0.635)
			(end -1.016 -0.635)
			(stroke
				(width 0.1)
				(type default)
			)
			(layer "F.Fab")
		)
		(fp_line
			(start -1.016 -0.635)
			(end -1.016 0.635)
			(stroke
				(width 0.1)
				(type default)
			)
			(layer "F.Fab")
		)
		(fp_line
			(start 1.016 0.635)
			(end 1.016 -0.635)
			(stroke
				(width 0.1)
				(type default)
			)
			(layer "F.Fab")
		)
		(fp_line
			(start -1.016 0.635)
			(end 1.016 0.635)
			(stroke
				(width 0.1)
				(type default)
			)
			(layer "F.Fab")
		)
		(pad "1" smd rect
			(at -0.8382 0 90)
			(size 0.9652 1.3716)
			(layers "F.Cu" "F.Mask" "F.Paste")
			(net "XP5R0V")
		)
		(pad "2" smd rect
			(at 0.8382 0 90)
			(size 0.9652 1.3716)
			(layers "F.Cu" "F.Mask" "F.Paste")
			(net "SG")
		)
		(zone
			(layer "F.Cu")
			(hatch none 0.5)
			(connect_pads
				(clearance 0)
			)
			(min_thickness 0.25)
			(keepout
				(tracks allowed)
				(vias not_allowed)
				(pads allowed)
				(copperpour not_allowed)
				(footprints allowed)
			)
			(placement
				(enabled no)
				(sheetname "")
			)
			(fill
				(thermal_gap 0.5)
				(thermal_bridge_width 0.5)
				(island_removal_mode 0)
			)
			(polygon
				(pts
					(xy 58.0644 -103.632) (xy 56.7944 -103.632) (xy 56.7944 -103.1748) (xy 58.0644 -103.1748)
				)
			)
		)
	)
)
